# T6G (Grand Teton) — schematic netlist excerpt (pin names and nets, part order shuffled) for the footprints in the layout excerpt that follows; sources: Cadence DE-HDL packaged netlist, KiCad conversion of 04192023_DAF0TMB3IC0_F0TG_MB_C_brd_V02_OCP.brd

C1239  Q_CAP  0.1UF 25V 10% X7R  pkg 0402  page 131 : A = P3V3_OCP_SFF ; B = GND
R185  Q_RES  0 5% CHIP  pkg 0402LF  page 82 : A = CPU0_CORETYPE2 ; B = FM_CPU0_CORETYPE2

(kicad_pcb
	(version 20260206)
	(generator "pcbnew")
	(generator_version "10.0")
	(general
		(thickness 1.6)
		(legacy_teardrops no)
	)
	(paper "A4")
	(title_block
		(title "04192023_DAF0TMB3IC0_F0TG_MB_C_brd_V02_OCP.brd")
		(comment 1 "Grand Teton / footprints 6411-6412 of 8354")
	)
	(layers
		(0 "F.Cu" signal "TOP")
		(4 "In1.Cu" signal "GND")
		(6 "In2.Cu" signal "IN1")
		(8 "In3.Cu" signal "GND1")
		(10 "In4.Cu" signal "IN2")
		(12 "In5.Cu" signal "GND2")
		(14 "In6.Cu" signal "IN3")
		(16 "In7.Cu" signal "GND3")
		(18 "In8.Cu" signal "VCC")
		(20 "In9.Cu" signal "VCC1")
		(22 "In10.Cu" signal "GND4")
		(24 "In11.Cu" signal "IN4")
		(26 "In12.Cu" signal "GND5")
		(28 "In13.Cu" signal "IN5")
		(30 "In14.Cu" signal "GND6")
		(32 "In15.Cu" signal "IN6")
		(34 "In16.Cu" signal "GND7")
		(2 "B.Cu" signal "BOTTOM")
		(9 "F.Adhes" user "F.Adhesive")
		(11 "B.Adhes" user "B.Adhesive")
		(13 "F.Paste" user "Package Geometry/Pastemask Top")
		(15 "B.Paste" user "Package Geometry/Pastemask Bottom")
		(5 "F.SilkS" user "Ref Des/Silkscreen Top")
		(7 "B.SilkS" user "Ref Des/Silkscreen Bottom")
		(1 "F.Mask" user "Board Geometry/Soldermask Top")
		(3 "B.Mask" user "Board Geometry/Soldermask Bottom")
		(17 "Dwgs.User" user "User.Drawings")
		(19 "Cmts.User" user "User.Comments")
		(21 "Eco1.User" user "User.Eco1")
		(23 "Eco2.User" user "User.Eco2")
		(25 "Edge.Cuts" user "Board Geometry/Outline")
		(27 "Margin" user)
		(31 "F.CrtYd" user "Package Geometry/Place Bound Top")
		(29 "B.CrtYd" user "Package Geometry/Place Bound Bottom")
		(35 "F.Fab" user "Ref Des/Assembly Top")
		(33 "B.Fab" user "Ref Des/Assembly Bottom")
	)
	(footprint ""
		(layer "B.Cu")
		(at 435.549802 -11.088116 180)
		(property "Reference" "C1239"
			(at 0 0 0)
			(layer "B.SilkS")
			(hide yes)
			(effects
				(font
					(size 1.27 1.27)
				)
				(justify mirror)
			)
		)
		(property "Value" ""
			(at 0 0 0)
			(layer "B.Fab")
			(effects
				(font
					(size 1.27 1.27)
				)
				(justify mirror)
			)
		)
		(duplicate_pad_numbers_are_jumpers no)
		(fp_line
			(start 0.7874 0.4064)
			(end 0.7874 -0.4064)
			(stroke
				(width 0.1524)
				(type default)
			)
			(layer "B.SilkS")
		)
		(fp_line
			(start 0.7874 -0.4064)
			(end -0.7874 -0.4064)
			(stroke
				(width 0.1524)
				(type default)
			)
			(layer "B.SilkS")
		)
		(fp_line
			(start -0.7874 0.4064)
			(end 0.7874 0.4064)
			(stroke
				(width 0.1524)
				(type default)
			)
			(layer "B.SilkS")
		)
		(fp_line
			(start -0.7874 -0.4064)
			(end -0.7874 0.4064)
			(stroke
				(width 0.1524)
				(type default)
			)
			(layer "B.SilkS")
		)
		(fp_line
			(start 0.67945 0.3048)
			(end 0.67945 -0.305054)
			(stroke
				(width 0.1)
				(type default)
			)
			(layer "B.Fab")
		)
		(fp_line
			(start 0.67945 -0.305054)
			(end 0.12065 -0.305054)
			(stroke
				(width 0.1)
				(type default)
			)
			(layer "B.Fab")
		)
		(fp_line
			(start 0.12065 0.3048)
			(end 0.67945 0.3048)
			(stroke
				(width 0.1)
				(type default)
			)
			(layer "B.Fab")
		)
		(fp_line
			(start 0.12065 0.2794)
			(end 0.12065 0.3048)
			(stroke
				(width 0.1)
				(type default)
			)
			(layer "B.Fab")
		)
		(fp_line
			(start 0.12065 -0.2794)
			(end -0.12065 -0.2794)
			(stroke
				(width 0.1)
				(type default)
			)
			(layer "B.Fab")
		)
		(fp_line
			(start 0.12065 -0.305054)
			(end 0.12065 -0.2794)
			(stroke
				(width 0.1)
				(type default)
			)
			(layer "B.Fab")
		)
		(fp_line
			(start -0.120396 0.3048)
			(end -0.120396 0.2794)
			(stroke
				(width 0.1)
				(type default)
			)
			(layer "B.Fab")
		)
		(fp_line
			(start -0.120396 0.2794)
			(end 0.12065 0.2794)
			(stroke
				(width 0.1)
				(type default)
			)
			(layer "B.Fab")
		)
		(fp_line
			(start -0.12065 -0.2794)
			(end -0.12065 -0.3048)
			(stroke
				(width 0.1)
				(type default)
			)
			(layer "B.Fab")
		)
		(fp_line
			(start -0.12065 -0.3048)
			(end -0.67945 -0.3048)
			(stroke
				(width 0.1)
				(type default)
			)
			(layer "B.Fab")
		)
		(fp_line
			(start -0.67945 0.3048)
			(end -0.120396 0.3048)
			(stroke
				(width 0.1)
				(type default)
			)
			(layer "B.Fab")
		)
		(fp_line
			(start -0.67945 -0.3048)
			(end -0.67945 0.3048)
			(stroke
				(width 0.1)
				(type default)
			)
			(layer "B.Fab")
		)
		(pad "1" smd circle
			(at 0.40005 0)
			(size 0 0)
			(layers "B.Cu" "B.Mask" "B.Paste")
			(net "P3V3_OCP_SFF")
		)
		(pad "2" smd circle
			(at -0.40005 0)
			(size 0 0)
			(layers "B.Cu" "B.Mask" "B.Paste")
			(net "GND")
		)
	)
	(footprint ""
		(layer "B.Cu")
		(at 189.865 -97.119948 -90)
		(property "Reference" "R185"
			(at 0 0 90)
			(layer "B.SilkS")
			(hide yes)
			(effects
				(font
					(size 1.27 1.27)
				)
				(justify mirror)
			)
		)
		(property "Value" ""
			(at 0 0 90)
			(layer "B.Fab")
			(effects
				(font
					(size 1.27 1.27)
				)
				(justify mirror)
			)
		)
		(duplicate_pad_numbers_are_jumpers no)
		(fp_line
			(start -0.7874 0.4064)
			(end 0.7874 0.4064)
			(stroke
				(width 0.1524)
				(type default)
			)
			(layer "B.SilkS")
		)
		(fp_line
			(start 0.7874 0.4064)
			(end 0.7874 -0.4064)
			(stroke
				(width 0.1524)
				(type default)
			)
			(layer "B.SilkS")
		)
		(fp_line
			(start -0.7874 -0.4064)
			(end -0.7874 0.4064)
			(stroke
				(width 0.1524)
				(type default)
			)
			(layer "B.SilkS")
		)
		(fp_line
			(start 0.7874 -0.4064)
			(end -0.7874 -0.4064)
			(stroke
				(width 0.1524)
				(type default)
			)
			(layer "B.SilkS")
		)
		(fp_line
			(start -0.67945 0.3048)
			(end -0.120396 0.3048)
			(stroke
				(width 0.1)
				(type default)
			)
			(layer "B.Fab")
		)
		(fp_line
			(start -0.120396 0.3048)
			(end -0.120396 0.2794)
			(stroke
				(width 0.1)
				(type default)
			)
			(layer "B.Fab")
		)
		(fp_line
			(start 0.12065 0.3048)
			(end 0.67945 0.3048)
			(stroke
				(width 0.1)
				(type default)
			)
			(layer "B.Fab")
		)
		(fp_line
			(start 0.67945 0.3048)
			(end 0.67945 -0.305054)
			(stroke
				(width 0.1)
				(type default)
			)
			(layer "B.Fab")
		)
		(fp_line
			(start -0.120396 0.2794)
			(end 0.12065 0.2794)
			(stroke
				(width 0.1)
				(type default)
			)
			(layer "B.Fab")
		)
		(fp_line
			(start 0.12065 0.2794)
			(end 0.12065 0.3048)
			(stroke
				(width 0.1)
				(type default)
			)
			(layer "B.Fab")
		)
		(fp_line
			(start -0.12065 -0.2794)
			(end -0.12065 -0.3048)
			(stroke
				(width 0.1)
				(type default)
			)
			(layer "B.Fab")
		)
		(fp_line
			(start 0.12065 -0.2794)
			(end -0.12065 -0.2794)
			(stroke
				(width 0.1)
				(type default)
			)
			(layer "B.Fab")
		)
		(fp_line
			(start -0.67945 -0.3048)
			(end -0.67945 0.3048)
			(stroke
				(width 0.1)
				(type default)
			)
			(layer "B.Fab")
		)
		(fp_line
			(start -0.12065 -0.3048)
			(end -0.67945 -0.3048)
			(stroke
				(width 0.1)
				(type default)
			)
			(layer "B.Fab")
		)
		(fp_line
			(start 0.12065 -0.305054)
			(end 0.12065 -0.2794)
			(stroke
				(width 0.1)
				(type default)
			)
			(layer "B.Fab")
		)
		(fp_line
			(start 0.67945 -0.305054)
			(end 0.12065 -0.305054)
			(stroke
				(width 0.1)
				(type default)
			)
			(layer "B.Fab")
		)
		(pad "1" smd circle
			(at 0.40005 0 90)
			(size 0 0)
			(layers "B.Cu" "B.Mask" "B.Paste")
			(net "CPU0_CORETYPE2")
		)
		(pad "2" smd circle
			(at -0.40005 0 90)
			(size 0 0)
			(layers "B.Cu" "B.Mask" "B.Paste")
			(net "FM_CPU0_CORETYPE2")
		)
	)
)
